# T6G (Grand Teton) — schematic netlist excerpt (pin names and nets, part order shuffled) for the footprints in the layout excerpt that follows; sources: Cadence DE-HDL packaged netlist, KiCad conversion of 04192023_DAF0TMB3IC0_F0TG_MB_C_brd_V02_OCP.brd

PC64  Q_CAP  220PF 50V 10% X7R  pkg 0402  page 226 : A = PVDD18_S5_P1_FB ; B = PVDD18_S5_P1_FB_RC
R3460  Q_RES  100K 1% EMPTY  pkg 0402LF  page 129 : A = GPU_NVS_PWR_BRAKE_N ; B = GND
C964  Q_CAP_DIFFBUS  DIFF BUS_0.22UF 6.3V 20% X6S  pkg C0201  page 63 : \1\ = P5E_CPU0_P1_TX_C_DN<0> ; \2\ = P5E_CPU0_P1_TX_DN<0>

(kicad_pcb
	(version 20260206)
	(generator "pcbnew")
	(generator_version "10.0")
	(general
		(thickness 1.6)
		(legacy_teardrops no)
	)
	(paper "A4")
	(title_block
		(title "04192023_DAF0TMB3IC0_F0TG_MB_C_brd_V02_OCP.brd")
		(comment 1 "Grand Teton / footprints 2053-2055 of 8354")
	)
	(layers
		(0 "F.Cu" signal "TOP")
		(4 "In1.Cu" signal "GND")
		(6 "In2.Cu" signal "IN1")
		(8 "In3.Cu" signal "GND1")
		(10 "In4.Cu" signal "IN2")
		(12 "In5.Cu" signal "GND2")
		(14 "In6.Cu" signal "IN3")
		(16 "In7.Cu" signal "GND3")
		(18 "In8.Cu" signal "VCC")
		(20 "In9.Cu" signal "VCC1")
		(22 "In10.Cu" signal "GND4")
		(24 "In11.Cu" signal "IN4")
		(26 "In12.Cu" signal "GND5")
		(28 "In13.Cu" signal "IN5")
		(30 "In14.Cu" signal "GND6")
		(32 "In15.Cu" signal "IN6")
		(34 "In16.Cu" signal "GND7")
		(2 "B.Cu" signal "BOTTOM")
		(9 "F.Adhes" user "F.Adhesive")
		(11 "B.Adhes" user "B.Adhesive")
		(13 "F.Paste" user "Package Geometry/Pastemask Top")
		(15 "B.Paste" user "Package Geometry/Pastemask Bottom")
		(5 "F.SilkS" user "Ref Des/Silkscreen Top")
		(7 "B.SilkS" user "Ref Des/Silkscreen Bottom")
		(1 "F.Mask" user "Board Geometry/Soldermask Top")
		(3 "B.Mask" user "Board Geometry/Soldermask Bottom")
		(17 "Dwgs.User" user "User.Drawings")
		(19 "Cmts.User" user "User.Comments")
		(21 "Eco1.User" user "User.Eco1")
		(23 "Eco2.User" user "User.Eco2")
		(25 "Edge.Cuts" user "Board Geometry/Outline")
		(27 "Margin" user)
		(31 "F.CrtYd" user "Package Geometry/Place Bound Top")
		(29 "B.CrtYd" user "Package Geometry/Place Bound Bottom")
		(35 "F.Fab" user "Ref Des/Assembly Top")
		(33 "B.Fab" user "Ref Des/Assembly Bottom")
	)
	(footprint ""
		(layer "F.Cu")
		(at 72.463914 -146.735292 180)
		(property "Reference" "PC64"
			(at 0 0 180)
			(layer "F.SilkS")
			(hide yes)
			(effects
				(font
					(size 1.27 1.27)
				)
			)
		)
		(property "Value" ""
			(at 0 0 180)
			(layer "F.Fab")
			(effects
				(font
					(size 1.27 1.27)
				)
			)
		)
		(duplicate_pad_numbers_are_jumpers no)
		(fp_line
			(start 0.7874 0.4064)
			(end -0.7874 0.4064)
			(stroke
				(width 0.1524)
				(type default)
			)
			(layer "F.SilkS")
		)
		(fp_line
			(start 0.7874 -0.4064)
			(end 0.7874 0.4064)
			(stroke
				(width 0.1524)
				(type default)
			)
			(layer "F.SilkS")
		)
		(fp_line
			(start -0.7874 0.4064)
			(end -0.7874 -0.4064)
			(stroke
				(width 0.1524)
				(type default)
			)
			(layer "F.SilkS")
		)
		(fp_line
			(start -0.7874 -0.4064)
			(end 0.7874 -0.4064)
			(stroke
				(width 0.1524)
				(type default)
			)
			(layer "F.SilkS")
		)
		(fp_line
			(start 0.67945 0.3048)
			(end 0.120396 0.3048)
			(stroke
				(width 0.1)
				(type default)
			)
			(layer "F.Fab")
		)
		(fp_line
			(start 0.67945 -0.3048)
			(end 0.67945 0.3048)
			(stroke
				(width 0.1)
				(type default)
			)
			(layer "F.Fab")
		)
		(fp_line
			(start 0.12065 -0.2794)
			(end 0.12065 -0.3048)
			(stroke
				(width 0.1)
				(type default)
			)
			(layer "F.Fab")
		)
		(fp_line
			(start 0.12065 -0.3048)
			(end 0.67945 -0.3048)
			(stroke
				(width 0.1)
				(type default)
			)
			(layer "F.Fab")
		)
		(fp_line
			(start 0.120396 0.3048)
			(end 0.120396 0.2794)
			(stroke
				(width 0.1)
				(type default)
			)
			(layer "F.Fab")
		)
		(fp_line
			(start 0.120396 0.2794)
			(end -0.12065 0.2794)
			(stroke
				(width 0.1)
				(type default)
			)
			(layer "F.Fab")
		)
		(fp_line
			(start -0.12065 0.3048)
			(end -0.67945 0.3048)
			(stroke
				(width 0.1)
				(type default)
			)
			(layer "F.Fab")
		)
		(fp_line
			(start -0.12065 0.2794)
			(end -0.12065 0.3048)
			(stroke
				(width 0.1)
				(type default)
			)
			(layer "F.Fab")
		)
		(fp_line
			(start -0.12065 -0.2794)
			(end 0.12065 -0.2794)
			(stroke
				(width 0.1)
				(type default)
			)
			(layer "F.Fab")
		)
		(fp_line
			(start -0.12065 -0.305054)
			(end -0.12065 -0.2794)
			(stroke
				(width 0.1)
				(type default)
			)
			(layer "F.Fab")
		)
		(fp_line
			(start -0.67945 0.3048)
			(end -0.67945 -0.305054)
			(stroke
				(width 0.1)
				(type default)
			)
			(layer "F.Fab")
		)
		(fp_line
			(start -0.67945 -0.305054)
			(end -0.12065 -0.305054)
			(stroke
				(width 0.1)
				(type default)
			)
			(layer "F.Fab")
		)
		(pad "1" smd circle
			(at -0.40005 0 180)
			(size 0 0)
			(layers "F.Cu" "F.Mask" "F.Paste")
			(net "PVDD18_S5_P1_FB")
		)
		(pad "2" smd circle
			(at 0.40005 0 180)
			(size 0 0)
			(layers "F.Cu" "F.Mask" "F.Paste")
			(net "PVDD18_S5_P1_FB_RC")
		)
	)
	(footprint ""
		(layer "F.Cu")
		(at 331.494892 -389.86206 180)
		(property "Reference" "C964"
			(at 0 0 180)
			(layer "F.SilkS")
			(hide yes)
			(effects
				(font
					(size 1.27 1.27)
				)
			)
		)
		(property "Value" ""
			(at 0 0 180)
			(layer "F.Fab")
			(effects
				(font
					(size 1.27 1.27)
				)
			)
		)
		(duplicate_pad_numbers_are_jumpers no)
		(fp_line
			(start 0.299974 0.150114)
			(end -0.299974 0.150114)
			(stroke
				(width 0.1)
				(type default)
			)
			(layer "F.Fab")
		)
		(fp_line
			(start 0.299974 -0.150114)
			(end 0.299974 0.150114)
			(stroke
				(width 0.1)
				(type default)
			)
			(layer "F.Fab")
		)
		(fp_line
			(start -0.299974 0.150114)
			(end -0.299974 -0.150114)
			(stroke
				(width 0.1)
				(type default)
			)
			(layer "F.Fab")
		)
		(fp_line
			(start -0.299974 -0.150114)
			(end 0.299974 -0.150114)
			(stroke
				(width 0.1)
				(type default)
			)
			(layer "F.Fab")
		)
		(pad "1" smd rect
			(at -0.2667 0 180)
			(size 0.3048 0.381)
			(layers "F.Cu" "F.Mask" "F.Paste")
			(net "P5E_CPU0_P1_TX_C_DN<0>")
		)
		(pad "2" smd rect
			(at 0.2667 0 180)
			(size 0.3048 0.381)
			(layers "F.Cu" "F.Mask" "F.Paste")
			(net "P5E_CPU0_P1_TX_DN<0>")
		)
	)
	(footprint ""
		(layer "F.Cu")
		(at 105.918 -426.466 90)
		(property "Reference" "R3460"
			(at 0 0 90)
			(layer "F.SilkS")
			(hide yes)
			(effects
				(font
					(size 1.27 1.27)
				)
			)
		)
		(property "Value" ""
			(at 0 0 90)
			(layer "F.Fab")
			(effects
				(font
					(size 1.27 1.27)
				)
			)
		)
		(duplicate_pad_numbers_are_jumpers no)
		(fp_line
			(start 0.7874 -0.4064)
			(end 0.7874 0.4064)
			(stroke
				(width 0.1524)
				(type default)
			)
			(layer "F.SilkS")
		)
		(fp_line
			(start -0.7874 -0.4064)
			(end 0.7874 -0.4064)
			(stroke
				(width 0.1524)
				(type default)
			)
			(layer "F.SilkS")
		)
		(fp_line
			(start 0.7874 0.4064)
			(end -0.7874 0.4064)
			(stroke
				(width 0.1524)
				(type default)
			)
			(layer "F.SilkS")
		)
		(fp_line
			(start -0.7874 0.4064)
			(end -0.7874 -0.4064)
			(stroke
				(width 0.1524)
				(type default)
			)
			(layer "F.SilkS")
		)
		(fp_line
			(start -0.12065 -0.305054)
			(end -0.12065 -0.2794)
			(stroke
				(width 0.1)
				(type default)
			)
			(layer "F.Fab")
		)
		(fp_line
			(start -0.67945 -0.305054)
			(end -0.12065 -0.305054)
			(stroke
				(width 0.1)
				(type default)
			)
			(layer "F.Fab")
		)
		(fp_line
			(start 0.67945 -0.3048)
			(end 0.67945 0.3048)
			(stroke
				(width 0.1)
				(type default)
			)
			(layer "F.Fab")
		)
		(fp_line
			(start 0.12065 -0.3048)
			(end 0.67945 -0.3048)
			(stroke
				(width 0.1)
				(type default)
			)
			(layer "F.Fab")
		)
		(fp_line
			(start 0.12065 -0.2794)
			(end 0.12065 -0.3048)
			(stroke
				(width 0.1)
				(type default)
			)
			(layer "F.Fab")
		)
		(fp_line
			(start -0.12065 -0.2794)
			(end 0.12065 -0.2794)
			(stroke
				(width 0.1)
				(type default)
			)
			(layer "F.Fab")
		)
		(fp_line
			(start 0.120396 0.2794)
			(end -0.12065 0.2794)
			(stroke
				(width 0.1)
				(type default)
			)
			(layer "F.Fab")
		)
		(fp_line
			(start -0.12065 0.2794)
			(end -0.12065 0.3048)
			(stroke
				(width 0.1)
				(type default)
			)
			(layer "F.Fab")
		)
		(fp_line
			(start 0.67945 0.3048)
			(end 0.120396 0.3048)
			(stroke
				(width 0.1)
				(type default)
			)
			(layer "F.Fab")
		)
		(fp_line
			(start 0.120396 0.3048)
			(end 0.120396 0.2794)
			(stroke
				(width 0.1)
				(type default)
			)
			(layer "F.Fab")
		)
		(fp_line
			(start -0.12065 0.3048)
			(end -0.67945 0.3048)
			(stroke
				(width 0.1)
				(type default)
			)
			(layer "F.Fab")
		)
		(fp_line
			(start -0.67945 0.3048)
			(end -0.67945 -0.305054)
			(stroke
				(width 0.1)
				(type default)
			)
			(layer "F.Fab")
		)
		(pad "1" smd circle
			(at -0.40005 0 90)
			(size 0 0)
			(layers "F.Cu" "F.Mask" "F.Paste")
			(net "GPU_NVS_PWR_BRAKE_N")
		)
		(pad "2" smd circle
			(at 0.40005 0 90)
			(size 0 0)
			(layers "F.Cu" "F.Mask" "F.Paste")
			(net "GND")
		)
	)
)
